# T6G (Grand Teton) — schematic netlist excerpt (pin names and nets, part order shuffled) for the footprints in the layout excerpt that follows; sources: Cadence DE-HDL packaged netlist, KiCad conversion of 04192023_DAF0TMB3IC0_F0TG_MB_C_brd_V02_OCP.brd

PC802  Q_CAPP  470UF 2.5V 20% SPCAP  pkg SMLF  page 225 : A = PVDD11_S3_P1 ; B = GND
C208  Q_CAP  0.001UF 50V 10% EMPTY  pkg C0402  page 27 : A = JTAG_CPU0_TDI ; B = GND

(kicad_pcb
	(version 20260206)
	(generator "pcbnew")
	(generator_version "10.0")
	(general
		(thickness 1.6)
		(legacy_teardrops no)
	)
	(paper "A4")
	(title_block
		(title "04192023_DAF0TMB3IC0_F0TG_MB_C_brd_V02_OCP.brd")
		(comment 1 "Grand Teton / footprints 7328-7329 of 8354")
	)
	(layers
		(0 "F.Cu" signal "TOP")
		(4 "In1.Cu" signal "GND")
		(6 "In2.Cu" signal "IN1")
		(8 "In3.Cu" signal "GND1")
		(10 "In4.Cu" signal "IN2")
		(12 "In5.Cu" signal "GND2")
		(14 "In6.Cu" signal "IN3")
		(16 "In7.Cu" signal "GND3")
		(18 "In8.Cu" signal "VCC")
		(20 "In9.Cu" signal "VCC1")
		(22 "In10.Cu" signal "GND4")
		(24 "In11.Cu" signal "IN4")
		(26 "In12.Cu" signal "GND5")
		(28 "In13.Cu" signal "IN5")
		(30 "In14.Cu" signal "GND6")
		(32 "In15.Cu" signal "IN6")
		(34 "In16.Cu" signal "GND7")
		(2 "B.Cu" signal "BOTTOM")
		(9 "F.Adhes" user "F.Adhesive")
		(11 "B.Adhes" user "B.Adhesive")
		(13 "F.Paste" user "Package Geometry/Pastemask Top")
		(15 "B.Paste" user "Package Geometry/Pastemask Bottom")
		(5 "F.SilkS" user "Ref Des/Silkscreen Top")
		(7 "B.SilkS" user "Ref Des/Silkscreen Bottom")
		(1 "F.Mask" user "Board Geometry/Soldermask Top")
		(3 "B.Mask" user "Board Geometry/Soldermask Bottom")
		(17 "Dwgs.User" user "User.Drawings")
		(19 "Cmts.User" user "User.Comments")
		(21 "Eco1.User" user "User.Eco1")
		(23 "Eco2.User" user "User.Eco2")
		(25 "Edge.Cuts" user "Board Geometry/Outline")
		(27 "Margin" user)
		(31 "F.CrtYd" user "Package Geometry/Place Bound Top")
		(29 "B.CrtYd" user "Package Geometry/Place Bound Bottom")
		(35 "F.Fab" user "Ref Des/Assembly Top")
		(33 "B.Fab" user "Ref Des/Assembly Bottom")
	)
	(footprint ""
		(layer "B.Cu")
		(at 380.536958 -208.530952 90)
		(property "Reference" "C208"
			(at 0 0 90)
			(layer "B.SilkS")
			(hide yes)
			(effects
				(font
					(size 1.27 1.27)
				)
				(justify mirror)
			)
		)
		(property "Value" ""
			(at 0 0 90)
			(layer "B.Fab")
			(effects
				(font
					(size 1.27 1.27)
				)
				(justify mirror)
			)
		)
		(duplicate_pad_numbers_are_jumpers no)
		(fp_line
			(start 0.7874 -0.4064)
			(end -0.7874 -0.4064)
			(stroke
				(width 0.1524)
				(type default)
			)
			(layer "B.SilkS")
		)
		(fp_line
			(start -0.7874 -0.4064)
			(end -0.7874 0.4064)
			(stroke
				(width 0.1524)
				(type default)
			)
			(layer "B.SilkS")
		)
		(fp_line
			(start 0.7874 0.4064)
			(end 0.7874 -0.4064)
			(stroke
				(width 0.1524)
				(type default)
			)
			(layer "B.SilkS")
		)
		(fp_line
			(start -0.7874 0.4064)
			(end 0.7874 0.4064)
			(stroke
				(width 0.1524)
				(type default)
			)
			(layer "B.SilkS")
		)
		(fp_line
			(start 0.67945 -0.305054)
			(end 0.12065 -0.305054)
			(stroke
				(width 0.1)
				(type default)
			)
			(layer "B.Fab")
		)
		(fp_line
			(start 0.12065 -0.305054)
			(end 0.12065 -0.2794)
			(stroke
				(width 0.1)
				(type default)
			)
			(layer "B.Fab")
		)
		(fp_line
			(start -0.12065 -0.3048)
			(end -0.67945 -0.3048)
			(stroke
				(width 0.1)
				(type default)
			)
			(layer "B.Fab")
		)
		(fp_line
			(start -0.67945 -0.3048)
			(end -0.67945 0.3048)
			(stroke
				(width 0.1)
				(type default)
			)
			(layer "B.Fab")
		)
		(fp_line
			(start 0.12065 -0.2794)
			(end -0.12065 -0.2794)
			(stroke
				(width 0.1)
				(type default)
			)
			(layer "B.Fab")
		)
		(fp_line
			(start -0.12065 -0.2794)
			(end -0.12065 -0.3048)
			(stroke
				(width 0.1)
				(type default)
			)
			(layer "B.Fab")
		)
		(fp_line
			(start 0.12065 0.2794)
			(end 0.12065 0.3048)
			(stroke
				(width 0.1)
				(type default)
			)
			(layer "B.Fab")
		)
		(fp_line
			(start -0.120396 0.2794)
			(end 0.12065 0.2794)
			(stroke
				(width 0.1)
				(type default)
			)
			(layer "B.Fab")
		)
		(fp_line
			(start 0.67945 0.3048)
			(end 0.67945 -0.305054)
			(stroke
				(width 0.1)
				(type default)
			)
			(layer "B.Fab")
		)
		(fp_line
			(start 0.12065 0.3048)
			(end 0.67945 0.3048)
			(stroke
				(width 0.1)
				(type default)
			)
			(layer "B.Fab")
		)
		(fp_line
			(start -0.120396 0.3048)
			(end -0.120396 0.2794)
			(stroke
				(width 0.1)
				(type default)
			)
			(layer "B.Fab")
		)
		(fp_line
			(start -0.67945 0.3048)
			(end -0.120396 0.3048)
			(stroke
				(width 0.1)
				(type default)
			)
			(layer "B.Fab")
		)
		(pad "1" smd circle
			(at 0.40005 0 270)
			(size 0 0)
			(layers "B.Cu" "B.Mask" "B.Paste")
			(net "JTAG_CPU0_TDI")
		)
		(pad "2" smd circle
			(at -0.40005 0 270)
			(size 0 0)
			(layers "B.Cu" "B.Mask" "B.Paste")
			(net "GND")
		)
	)
	(footprint ""
		(layer "B.Cu")
		(at 175.836834 -343.785952 -90)
		(property "Reference" "PC802"
			(at 7.354316 -3.474466 270)
			(unlocked yes)
			(layer "B.SilkS")
			(effects
				(font
					(size 0.7874 0.5842)
					(thickness 0.1524)
				)
				(justify left mirror)
			)
		)
		(property "Value" ""
			(at 0 0 90)
			(layer "B.Fab")
			(effects
				(font
					(size 1.27 1.27)
				)
				(justify mirror)
			)
		)
		(duplicate_pad_numbers_are_jumpers no)
		(fp_line
			(start -4.533392 2.249932)
			(end 4.533392 2.249932)
			(stroke
				(width 0.1524)
				(type default)
			)
			(layer "B.SilkS")
		)
		(fp_line
			(start 4.533392 2.249932)
			(end 4.533392 -2.249932)
			(stroke
				(width 0.1524)
				(type default)
			)
			(layer "B.SilkS")
		)
		(fp_line
			(start -4.533392 -2.249932)
			(end -4.533392 2.249932)
			(stroke
				(width 0.1524)
				(type default)
			)
			(layer "B.SilkS")
		)
		(fp_line
			(start 4.533392 -2.249932)
			(end -4.533392 -2.249932)
			(stroke
				(width 0.1524)
				(type default)
			)
			(layer "B.SilkS")
		)
		(fp_rect
			(start 5.39242 2.326132)
			(end 4.533392 -2.326132)
			(stroke
				(width 0)
				(type default)
			)
			(fill yes)
			(layer "B.SilkS")
		)
		(fp_line
			(start -3.750056 2.249932)
			(end 3.750056 2.249932)
			(stroke
				(width 0.1)
				(type default)
			)
			(layer "B.Fab")
		)
		(fp_line
			(start 3.750056 2.249932)
			(end 3.750056 -2.249932)
			(stroke
				(width 0.1)
				(type default)
			)
			(layer "B.Fab")
		)
		(fp_line
			(start -3.750056 -2.249932)
			(end -3.750056 2.249932)
			(stroke
				(width 0.1)
				(type default)
			)
			(layer "B.Fab")
		)
		(fp_line
			(start 3.750056 -2.249932)
			(end -3.750056 -2.249932)
			(stroke
				(width 0.1)
				(type default)
			)
			(layer "B.Fab")
		)
		(fp_text user "+"
			(at 6.322314 0.786384 180)
			(unlocked yes)
			(layer "B.SilkS")
			(effects
				(font
					(size 1.905 1.4224)
					(thickness 0.1524)
				)
				(justify left mirror)
			)
		)
		(fp_text user "-"
			(at -4.8514 -0.14605 270)
			(unlocked yes)
			(layer "B.SilkS")
			(effects
				(font
					(size 1.905 1.4224)
					(thickness 0.1524)
				)
				(justify left mirror)
			)
		)
		(fp_text user "+"
			(at 6.322314 0.786384 180)
			(unlocked yes)
			(layer "B.Fab")
			(effects
				(font
					(size 1.905 1.4224)
					(thickness 0.1524)
				)
				(justify left mirror)
			)
		)
		(fp_text user "-"
			(at -4.8514 -0.14605 270)
			(unlocked yes)
			(layer "B.Fab")
			(effects
				(font
					(size 1.905 1.4224)
					(thickness 0.1524)
				)
				(justify left mirror)
			)
		)
		(pad "1" smd rect
			(at 3.199892 0 90)
			(size 2.413 2.8194)
			(layers "B.Cu" "B.Mask" "B.Paste")
			(net "PVDD11_S3_P1")
		)
		(pad "2" smd rect
			(at -3.199892 0 90)
			(size 2.413 2.8194)
			(layers "B.Cu" "B.Mask" "B.Paste")
			(net "GND")
		)
	)
)
